FILE_TYPE = CONNECTIVITY;
{Allegro Design Entry HDL 17.4-2019 S026 (4007227) 1/17/2022}
"PAGE_NUMBER" = 18;
0"NC";
1"M_I_CPU0_SA_DQ<31:0>";
2"M_I_CPU0_SB_DQ<31:0>";
3"M_I_CPU0_SA_CB<7:0>";
4"M_I_CPU0_SB_CB<7:0>";
5"M_I_CPU0_SA_DQS_DP<9:0>";
6"M_I_CPU0_SA_DQS_DN<9:0>";
7"M_I_CPU0_SB_DQS_DP<9:0>";
8"M_I_CPU0_SB_DQS_DN<9:0>";
9"M_I_CPU0_SA_CA<6:0>";
10"M_I_CPU0_SB_CA<6:0>";
11"M_I_CPU0_ALERT_N";
12"M_I_CPU0_ALERT_R_N";
13"TP_M_I_CPU0_SA_TEST39I";
14"M_I_CPU0_CLK_DP<0>";
15"M_I_CPU0_CLK_DN<0>";
16"M_I_CPU0_SA_CS_N<0>";
17"M_I_CPU0_SA_CS_N<1>";
18"M_I_CPU0_SA_RSP<0>";
19"M_I_CPU0_SA_PAR";
20"M_I_CPU0_SB_CS_N<0>";
21"M_I_CPU0_SB_CS_N<1>";
22"M_I_CPU0_SB_RSP<0>";
23"M_I_CPU0_SB_PAR";
24"M_I_CPU0_RESET_N";
25"M_I_CPU0_SB_DQS_DN<9>";
26"M_I_CPU0_SB_DQS_DN<8>";
27"M_I_CPU0_SB_CA<6>";
28"M_I_CPU0_SA_CA<6>";
29"M_I_CPU0_SB_CA<5>";
30"M_I_CPU0_SA_CA<5>";
31"M_I_CPU0_SB_CA<4>";
32"M_I_CPU0_SA_CA<4>";
33"M_I_CPU0_SB_CA<3>";
34"M_I_CPU0_SA_CA<3>";
35"M_I_CPU0_SB_CA<2>";
36"M_I_CPU0_SA_CA<2>";
37"M_I_CPU0_SB_CA<1>";
38"M_I_CPU0_SA_CA<1>";
39"M_I_CPU0_SB_CA<0>";
40"M_I_CPU0_SA_CA<0>";
41"M_I_CPU0_SB_DQS_DP<9>";
42"M_I_CPU0_SB_DQS_DN<7>";
43"M_I_CPU0_SB_DQS_DN<6>";
44"M_I_CPU0_SB_DQS_DN<5>";
45"M_I_CPU0_SB_DQS_DN<4>";
46"M_I_CPU0_SA_DQS_DN<9>";
47"M_I_CPU0_SB_DQS_DN<3>";
48"M_I_CPU0_SB_DQS_DN<2>";
49"M_I_CPU0_SB_DQS_DN<1>";
50"M_I_CPU0_SB_DQS_DN<0>";
51"M_I_CPU0_SB_DQS_DP<8>";
52"M_I_CPU0_SB_DQS_DP<7>";
53"M_I_CPU0_SB_DQS_DP<6>";
54"M_I_CPU0_SB_DQS_DP<5>";
55"M_I_CPU0_SB_DQS_DP<4>";
56"M_I_CPU0_SA_DQS_DP<9>";
57"M_I_CPU0_SB_DQS_DP<3>";
58"M_I_CPU0_SB_DQS_DP<2>";
59"M_I_CPU0_SB_DQS_DP<1>";
60"M_I_CPU0_SB_DQS_DP<0>";
61"M_I_CPU0_SA_DQS_DN<4>";
62"M_I_CPU0_SA_DQS_DN<3>";
63"M_I_CPU0_SA_DQS_DN<2>";
64"M_I_CPU0_SA_DQS_DN<1>";
65"M_I_CPU0_SA_DQS_DN<0>";
66"M_I_CPU0_SA_DQS_DN<8>";
67"M_I_CPU0_SA_DQS_DN<7>";
68"M_I_CPU0_SA_DQS_DN<6>";
69"M_I_CPU0_SA_DQS_DN<5>";
70"M_I_CPU0_SA_DQS_DP<8>";
71"M_I_CPU0_SA_DQS_DP<7>";
72"M_I_CPU0_SA_DQS_DP<6>";
73"M_I_CPU0_SA_DQS_DP<5>";
74"M_I_CPU0_SA_DQS_DP<4>";
75"M_I_CPU0_SA_DQS_DP<0>";
76"M_I_CPU0_SA_DQS_DP<3>";
77"M_I_CPU0_SA_DQS_DP<2>";
78"M_I_CPU0_SA_DQS_DP<1>";
79"M_I_CPU0_SB_CB<2>";
80"M_I_CPU0_SA_CB<7>";
81"M_I_CPU0_SB_CB<1>";
82"M_I_CPU0_SB_CB<0>";
83"M_I_CPU0_SB_CB<7>";
84"M_I_CPU0_SB_CB<6>";
85"M_I_CPU0_SB_CB<5>";
86"M_I_CPU0_SB_CB<4>";
87"M_I_CPU0_SB_CB<3>";
88"M_I_CPU0_SB_DQ<22>";
89"M_I_CPU0_SB_DQ<21>";
90"M_I_CPU0_SA_CB<6>";
91"M_I_CPU0_SB_DQ<31>";
92"M_I_CPU0_SA_CB<5>";
93"M_I_CPU0_SB_DQ<30>";
94"M_I_CPU0_SA_CB<4>";
95"M_I_CPU0_SA_CB<3>";
96"M_I_CPU0_SA_CB<2>";
97"M_I_CPU0_SA_CB<1>";
98"M_I_CPU0_SA_CB<0>";
99"M_I_CPU0_SB_DQ<29>";
100"M_I_CPU0_SB_DQ<28>";
101"M_I_CPU0_SB_DQ<27>";
102"M_I_CPU0_SB_DQ<26>";
103"M_I_CPU0_SB_DQ<25>";
104"M_I_CPU0_SB_DQ<24>";
105"M_I_CPU0_SB_DQ<23>";
106"M_I_CPU0_SB_DQ<5>";
107"M_I_CPU0_SB_DQ<11>";
108"M_I_CPU0_SB_DQ<4>";
109"M_I_CPU0_SB_DQ<10>";
110"M_I_CPU0_SB_DQ<3>";
111"M_I_CPU0_SB_DQ<20>";
112"M_I_CPU0_SB_DQ<2>";
113"M_I_CPU0_SB_DQ<19>";
114"M_I_CPU0_SB_DQ<18>";
115"M_I_CPU0_SB_DQ<17>";
116"M_I_CPU0_SB_DQ<16>";
117"M_I_CPU0_SB_DQ<9>";
118"M_I_CPU0_SB_DQ<15>";
119"M_I_CPU0_SB_DQ<8>";
120"M_I_CPU0_SB_DQ<14>";
121"M_I_CPU0_SB_DQ<7>";
122"M_I_CPU0_SB_DQ<13>";
123"M_I_CPU0_SB_DQ<6>";
124"M_I_CPU0_SB_DQ<12>";
125"M_I_CPU0_SA_DQ<17>";
126"M_I_CPU0_SA_DQ<28>";
127"M_I_CPU0_SA_DQ<16>";
128"M_I_CPU0_SA_DQ<27>";
129"M_I_CPU0_SA_DQ<26>";
130"M_I_CPU0_SA_DQ<25>";
131"M_I_CPU0_SA_DQ<24>";
132"M_I_CPU0_SB_DQ<1>";
133"M_I_CPU0_SA_DQ<23>";
134"M_I_CPU0_SB_DQ<0>";
135"M_I_CPU0_SA_DQ<22>";
136"M_I_CPU0_SA_DQ<21>";
137"M_I_CPU0_SA_DQ<20>";
138"M_I_CPU0_SA_DQ<31>";
139"M_I_CPU0_SA_DQ<30>";
140"M_I_CPU0_SA_DQ<19>";
141"M_I_CPU0_SA_DQ<18>";
142"M_I_CPU0_SA_DQ<29>";
143"M_I_CPU0_SA_DQ<5>";
144"M_I_CPU0_SA_DQ<4>";
145"M_I_CPU0_SA_DQ<3>";
146"M_I_CPU0_SA_DQ<15>";
147"M_I_CPU0_SA_DQ<2>";
148"M_I_CPU0_SA_DQ<14>";
149"M_I_CPU0_SA_DQ<1>";
150"M_I_CPU0_SA_DQ<13>";
151"M_I_CPU0_SA_DQ<0>";
152"M_I_CPU0_SA_DQ<12>";
153"M_I_CPU0_SA_DQ<11>";
154"M_I_CPU0_SA_DQ<10>";
155"M_I_CPU0_SA_DQ<9>";
156"M_I_CPU0_SA_DQ<8>";
157"M_I_CPU0_SA_DQ<7>";
158"M_I_CPU0_SA_DQ<6>";
%"GENOA_SP5"
"9","(-4525,3600)","0","pure_quanta","I159";
;
LOCATION"U25"
$SEC"9"
CDS_SEC"9"
PART_TYPE"SMLF"
MATERIAL"IO"
VALUE"SOCKET6096_13568-001"
CDS_LIB"pure_quanta"
CDS_LMAN_SYM_OUTLINE"-650,2525,650,-2525"
NEEDS_NO_SIZE"TRUE"
PART_NUMBER"DGA^6000030";
"TEST39I"
$PN"BF21"13;
"MIA_DATA5"
$PN"K21"143;
"MIA_DATA17"
$PN"V21"125;
"MIA_DATA28"
$PN"AG19"126;
"MIA_DQS_H0"
$PN"G19"75;
"MIA_DQS_L4"
$PN"AM20"61;
"MIB_CHECK2"
$PN"CA19"79;
"MIB_DATA5"
$PN"CG21"106;
"MIB_DATA11"
$PN"CK21"107;
"MIB_DATA22"
$PN"CW19"88;
"MI_ALERT_L"
$PN"AT21"12;
"MIA0_RSP_L"
$PN"BN21"18;
"MIA1_RSP_L"
$PN"BP21"0;
"MIA_CHECK7"
$PN"AR21"80;
"MIA_DATA4"
$PN"J19"144;
"MIA_DATA16"
$PN"U19"127;
"MIA_DATA27"
$PN"AE21"128;
"MIA_DQS_L3"
$PN"AF20"62;
"MIB_CHECK1"
$PN"CA21"81;
"MIB_DATA4"
$PN"CF20"108;
"MIB_DATA10"
$PN"CJ19"109;
"MIB_DATA21"
$PN"CW21"89;
"MIB_PAR"
$PN"BL21"23;
"MIA_CHECK6"
$PN"AP20"90;
"MIA_DATA3"
$PN"G21"145;
"MIA_DATA15"
$PN"U21"146;
"MIA_DATA26"
$PN"AD20"129;
"MIA_DQS_L2"
$PN"Y20"63;
"MIA_PAR"
$PN"BC21"19;
"MIB1_CS_L1"
$PN"BM20"0;
"MIB_CHECK0"
$PN"BY20"82;
"MIB_DATA3"
$PN"CD21"110;
"MIB_DATA20"
$PN"CV20"111;
"MIB_DATA31"
$PN"DF21"91;
"MIB_DQS_H9"
$PN"BV20"41;
"MIA_CHECK5"
$PN"AP21"92;
"MIA_DATA2"
$PN"F20"147;
"MIA_DATA14"
$PN"T20"148;
"MIA_DATA25"
$PN"AD21"130;
"MIA_DQS_L1"
$PN"P20"64;
"MIB0_CS_L1"
$PN"BN19"21;
"MIB1_CS_L0"
$PN"BL19"0;
"MIB_DATA2"
$PN"CC19"112;
"MIB_DATA30"
$PN"DE19"93;
"MIB_DQS_H8"
$PN"DD21"51;
"MIA_CHECK4"
$PN"AN19"94;
"MIA_DATA1"
$PN"F21"149;
"MIA_DATA13"
$PN"T21"150;
"MIA_DATA24"
$PN"AC19"131;
"MIA_DQS_L0"
$PN"H20"65;
"MIB0_CS_L0"
$PN"BM21"20;
"MIB_DATA1"
$PN"CC21"132;
"MIB_DQS_H7"
$PN"CV21"52;
"MIA_CHECK3"
$PN"AL21"95;
"MIA_DATA0"
$PN"E19"151;
"MIA_DATA12"
$PN"R19"152;
"MIA_DATA23"
$PN"AC21"133;
"MIB_DATA0"
$PN"CB20"134;
"MIB_DQS_H6"
$PN"CM21"53;
"MI_RESET_L"
$PN"AU21"24;
"MI0_CLK_L"
$PN"BD20"15;
"MI1_CLK_L"
$PN"BG19"0;
"MIA_CHECK2"
$PN"AK20"96;
"MIA_DATA11"
$PN"N21"153;
"MIA_DATA22"
$PN"AB20"135;
"MIB_DQS_H5"
$PN"CF21"54;
"MIB_DQS_L9"
$PN"BW19"25;
"MIA_CHECK1"
$PN"AK21"97;
"MIA_DATA10"
$PN"M20"154;
"MIA_DATA21"
$PN"AB21"136;
"MIB_DQS_H4"
$PN"BY21"55;
"MIB_DQS_L8"
$PN"DC21"26;
"MIA_CHECK0"
$PN"AJ19"98;
"MIA_DATA20"
$PN"AA19"137;
"MIA_DATA31"
$PN"AJ21"138;
"MIA_DQS_H9"
$PN"AN21"56;
"MIB_CA6"
$PN"BK20"27;
"MIB_DQS_H3"
$PN"DB20"57;
"MIB_DQS_L7"
$PN"CU21"42;
"MIA0_CS_L1"
$PN"AV21"17;
"MIA1_CS_L1"
$PN"AW21"0;
"MIA_CA6"
$PN"BB21"28;
"MIA_DATA30"
$PN"AH20"139;
"MIA_DQS_H8"
$PN"AG21"70;
"MIB_CA5"
$PN"BK21"29;
"MIB_DATA19"
$PN"CT21"113;
"MIB_DQS_H2"
$PN"CT20"58;
"MIB_DQS_L6"
$PN"CL21"43;
"MI0_CLK_H"
$PN"BC19"14;
"MI1_CLK_H"
$PN"BF20"0;
"MIA0_CS_L0"
$PN"AU19"16;
"MIA1_CS_L0"
$PN"AV20"0;
"MIA_CA5"
$PN"BB20"30;
"MIA_DQS_H7"
$PN"AA21"71;
"MIB_CA4"
$PN"BJ21"31;
"MIB_DATA18"
$PN"CR19"114;
"MIB_DATA29"
$PN"DE21"99;
"MIB_DQS_H1"
$PN"CK20"59;
"MIB_DQS_L5"
$PN"CE21"44;
"MIA_CA4"
$PN"BA19"32;
"MIA_DQS_H6"
$PN"R21"72;
"MIB1_RSP_L"
$PN"BR19"0;
"MIB_CA3"
$PN"BJ19"33;
"MIB_DATA17"
$PN"CR21"115;
"MIB_DATA28"
$PN"DD20"100;
"MIB_DQS_H0"
$PN"CD20"60;
"MIB_DQS_L4"
$PN"BW21"45;
"MIA_CA3"
$PN"BA21"34;
"MIA_DQS_H5"
$PN"J21"73;
"MIA_DQS_L9"
$PN"AM21"46;
"MIB0_RSP_L"
$PN"BP20"22;
"MIB_CA2"
$PN"BH20"35;
"MIB_CHECK7"
$PN"BV21"83;
"MIB_DATA16"
$PN"CP20"116;
"MIB_DATA27"
$PN"DB21"101;
"MIB_DQS_L3"
$PN"DC19"47;
"MIA_CA2"
$PN"AY21"36;
"MIA_DATA9"
$PN"M21"155;
"MIA_DQS_H4"
$PN"AL19"74;
"MIA_DQS_L8"
$PN"AF21"66;
"MIB_CA1"
$PN"BH21"37;
"MIB_CHECK6"
$PN"BU19"84;
"MIB_DATA9"
$PN"CJ21"117;
"MIB_DATA15"
$PN"CP21"118;
"MIB_DATA26"
$PN"DA19"102;
"MIB_DQS_L2"
$PN"CU19"48;
"MIA_CA1"
$PN"AY20"38;
"MIA_DATA8"
$PN"L19"156;
"MIA_DQS_H3"
$PN"AE19"76;
"MIA_DQS_L7"
$PN"Y21"67;
"MIB_CA0"
$PN"BG21"39;
"MIB_CHECK5"
$PN"BU21"85;
"MIB_DATA8"
$PN"CH20"119;
"MIB_DATA14"
$PN"CN19"120;
"MIB_DATA25"
$PN"DA21"103;
"MIB_DQS_L1"
$PN"CL19"49;
"MIA_CA0"
$PN"AW19"40;
"MIA_DATA7"
$PN"L21"157;
"MIA_DATA19"
$PN"W21"140;
"MIA_DQS_H2"
$PN"W19"77;
"MIA_DQS_L6"
$PN"P21"68;
"MIB_CHECK4"
$PN"BT20"86;
"MIB_DATA7"
$PN"CH21"121;
"MIB_DATA13"
$PN"CN21"122;
"MIB_DATA24"
$PN"CY20"104;
"MIB_DQS_L0"
$PN"CE19"50;
"MIA_DATA6"
$PN"K20"158;
"MIA_DATA18"
$PN"V20"141;
"MIA_DATA29"
$PN"AH21"142;
"MIA_DQS_H1"
$PN"N19"78;
"MIA_DQS_L5"
$PN"H21"69;
"MIB_CHECK3"
$PN"CB21"87;
"MIB_DATA6"
$PN"CG19"123;
"MIB_DATA12"
$PN"CM20"124;
"MIB_DATA23"
$PN"CY21"105;
%"TAP"
"1","(-3250,5975)","0","mstr_standard","I162";
;
CDS_LIB"mstr_standard"
BODY_TYPE"PLUMBING"
HDL_TAP"TRUE";
"B \NAC \NWC"1;
"S \NAC"
BN"0"151;
%"TAP"
"1","(-3250,5925)","0","mstr_standard","I163";
;
CDS_LIB"mstr_standard"
BODY_TYPE"PLUMBING"
HDL_TAP"TRUE";
"B \NAC \NWC"1;
"S \NAC"
BN"1"149;
%"TAP"
"1","(-3250,5775)","0","mstr_standard","I164";
;
CDS_LIB"mstr_standard"
BODY_TYPE"PLUMBING"
HDL_TAP"TRUE";
"B \NAC \NWC"1;
"S \NAC"
BN"4"144;
%"TAP"
"1","(-3250,5825)","0","mstr_standard","I165";
;
CDS_LIB"mstr_standard"
BODY_TYPE"PLUMBING"
HDL_TAP"TRUE";
"B \NAC \NWC"1;
"S \NAC"
BN"3"145;
%"TAP"
"1","(-3250,5875)","0","mstr_standard","I166";
;
CDS_LIB"mstr_standard"
BODY_TYPE"PLUMBING"
HDL_TAP"TRUE";
"B \NAC \NWC"1;
"S \NAC"
BN"2"147;
%"TAP"
"1","(-3250,5675)","0","mstr_standard","I167";
;
CDS_LIB"mstr_standard"
BODY_TYPE"PLUMBING"
HDL_TAP"TRUE";
"B \NAC \NWC"1;
"S \NAC"
BN"6"158;
%"TAP"
"1","(-3250,5725)","0","mstr_standard","I168";
;
CDS_LIB"mstr_standard"
BODY_TYPE"PLUMBING"
HDL_TAP"TRUE";
"B \NAC \NWC"1;
"S \NAC"
BN"5"143;
%"TAP"
"1","(-3250,5525)","0","mstr_standard","I169";
;
CDS_LIB"mstr_standard"
BODY_TYPE"PLUMBING"
HDL_TAP"TRUE";
"B \NAC \NWC"1;
"S \NAC"
BN"8"156;
%"TAP"
"1","(-3250,5625)","0","mstr_standard","I170";
;
CDS_LIB"mstr_standard"
BODY_TYPE"PLUMBING"
HDL_TAP"TRUE";
"B \NAC \NWC"1;
"S \NAC"
BN"7"157;
%"TAP"
"1","(-3250,5425)","0","mstr_standard","I171";
;
CDS_LIB"mstr_standard"
BODY_TYPE"PLUMBING"
HDL_TAP"TRUE";
"B \NAC \NWC"1;
"S \NAC"
BN"10"154;
%"TAP"
"1","(-3250,5475)","0","mstr_standard","I172";
;
CDS_LIB"mstr_standard"
BODY_TYPE"PLUMBING"
HDL_TAP"TRUE";
"B \NAC \NWC"1;
"S \NAC"
BN"9"155;
%"TAP"
"1","(-3250,5275)","0","mstr_standard","I173";
;
CDS_LIB"mstr_standard"
BODY_TYPE"PLUMBING"
HDL_TAP"TRUE";
"B \NAC \NWC"1;
"S \NAC"
BN"13"150;
%"TAP"
"1","(-3250,5325)","0","mstr_standard","I174";
;
CDS_LIB"mstr_standard"
BODY_TYPE"PLUMBING"
HDL_TAP"TRUE";
"B \NAC \NWC"1;
"S \NAC"
BN"12"152;
%"TAP"
"1","(-3250,5375)","0","mstr_standard","I175";
;
CDS_LIB"mstr_standard"
BODY_TYPE"PLUMBING"
HDL_TAP"TRUE";
"B \NAC \NWC"1;
"S \NAC"
BN"11"153;
%"TAP"
"1","(-3250,5225)","0","mstr_standard","I176";
;
CDS_LIB"mstr_standard"
BODY_TYPE"PLUMBING"
HDL_TAP"TRUE";
"B \NAC \NWC"1;
"S \NAC"
BN"14"148;
%"TAP"
"1","(-3250,5175)","0","mstr_standard","I177";
;
CDS_LIB"mstr_standard"
BODY_TYPE"PLUMBING"
HDL_TAP"TRUE";
"B \NAC \NWC"1;
"S \NAC"
BN"15"146;
%"TAP"
"1","(-3250,5075)","0","mstr_standard","I178";
;
CDS_LIB"mstr_standard"
BODY_TYPE"PLUMBING"
HDL_TAP"TRUE";
"B \NAC \NWC"1;
"S \NAC"
BN"16"127;
%"TAP"
"1","(-3250,5025)","0","mstr_standard","I179";
;
CDS_LIB"mstr_standard"
BODY_TYPE"PLUMBING"
HDL_TAP"TRUE";
"B \NAC \NWC"1;
"S \NAC"
BN"17"125;
%"TAP"
"1","(-3250,4875)","0","mstr_standard","I180";
;
CDS_LIB"mstr_standard"
BODY_TYPE"PLUMBING"
HDL_TAP"TRUE";
"B \NAC \NWC"1;
"S \NAC"
BN"20"137;
%"TAP"
"1","(-3250,4925)","0","mstr_standard","I181";
;
CDS_LIB"mstr_standard"
BODY_TYPE"PLUMBING"
HDL_TAP"TRUE";
"B \NAC \NWC"1;
"S \NAC"
BN"19"140;
%"TAP"
"1","(-3250,4975)","0","mstr_standard","I182";
;
CDS_LIB"mstr_standard"
BODY_TYPE"PLUMBING"
HDL_TAP"TRUE";
"B \NAC \NWC"1;
"S \NAC"
BN"18"141;
%"TAP"
"1","(-3250,4775)","0","mstr_standard","I183";
;
CDS_LIB"mstr_standard"
BODY_TYPE"PLUMBING"
HDL_TAP"TRUE";
"B \NAC \NWC"1;
"S \NAC"
BN"22"135;
%"TAP"
"1","(-3250,4825)","0","mstr_standard","I184";
;
CDS_LIB"mstr_standard"
BODY_TYPE"PLUMBING"
HDL_TAP"TRUE";
"B \NAC \NWC"1;
"S \NAC"
BN"21"136;
%"TAP"
"1","(-3250,4725)","0","mstr_standard","I185";
;
CDS_LIB"mstr_standard"
BODY_TYPE"PLUMBING"
HDL_TAP"TRUE";
"B \NAC \NWC"1;
"S \NAC"
BN"23"133;
%"TAP"
"1","(-3250,4625)","0","mstr_standard","I186";
;
CDS_LIB"mstr_standard"
BODY_TYPE"PLUMBING"
HDL_TAP"TRUE";
"B \NAC \NWC"1;
"S \NAC"
BN"24"131;
%"TAP"
"1","(-3250,4525)","0","mstr_standard","I187";
;
CDS_LIB"mstr_standard"
BODY_TYPE"PLUMBING"
HDL_TAP"TRUE";
"B \NAC \NWC"1;
"S \NAC"
BN"26"129;
%"TAP"
"1","(-3250,4575)","0","mstr_standard","I188";
;
CDS_LIB"mstr_standard"
BODY_TYPE"PLUMBING"
HDL_TAP"TRUE";
"B \NAC \NWC"1;
"S \NAC"
BN"25"130;
%"TAP"
"1","(-3250,4375)","0","mstr_standard","I189";
;
CDS_LIB"mstr_standard"
BODY_TYPE"PLUMBING"
HDL_TAP"TRUE";
"B \NAC \NWC"1;
"S \NAC"
BN"29"142;
%"TAP"
"1","(-3250,4425)","0","mstr_standard","I190";
;
CDS_LIB"mstr_standard"
BODY_TYPE"PLUMBING"
HDL_TAP"TRUE";
"B \NAC \NWC"1;
"S \NAC"
BN"28"126;
%"TAP"
"1","(-3250,4475)","0","mstr_standard","I191";
;
CDS_LIB"mstr_standard"
BODY_TYPE"PLUMBING"
HDL_TAP"TRUE";
"B \NAC \NWC"1;
"S \NAC"
BN"27"128;
%"TAP"
"1","(-3250,4325)","0","mstr_standard","I192";
;
CDS_LIB"mstr_standard"
BODY_TYPE"PLUMBING"
HDL_TAP"TRUE";
"B \NAC \NWC"1;
"S \NAC"
BN"30"139;
%"TAP"
"1","(-3250,4275)","0","mstr_standard","I193";
;
CDS_LIB"mstr_standard"
BODY_TYPE"PLUMBING"
HDL_TAP"TRUE";
"B \NAC \NWC"1;
"S \NAC"
BN"31"138;
%"TAP"
"1","(-3250,4175)","0","mstr_standard","I194";
;
CDS_LIB"mstr_standard"
BODY_TYPE"PLUMBING"
HDL_TAP"TRUE";
"B \NAC \NWC"2;
"S \NAC"
BN"0"134;
%"TAP"
"1","(-3250,4125)","0","mstr_standard","I195";
;
CDS_LIB"mstr_standard"
BODY_TYPE"PLUMBING"
HDL_TAP"TRUE";
"B \NAC \NWC"2;
"S \NAC"
BN"1"132;
%"TAP"
"1","(-3250,3975)","0","mstr_standard","I197";
;
CDS_LIB"mstr_standard"
BODY_TYPE"PLUMBING"
HDL_TAP"TRUE";
"B \NAC \NWC"2;
"S \NAC"
BN"4"108;
%"TAP"
"1","(-3250,4075)","0","mstr_standard","I198";
;
CDS_LIB"mstr_standard"
BODY_TYPE"PLUMBING"
HDL_TAP"TRUE";
"B \NAC \NWC"2;
"S \NAC"
BN"2"112;
%"TAP"
"1","(-3250,4025)","0","mstr_standard","I199";
;
CDS_LIB"mstr_standard"
BODY_TYPE"PLUMBING"
HDL_TAP"TRUE";
"B \NAC \NWC"2;
"S \NAC"
BN"3"110;
%"TAP"
"1","(-3250,3925)","0","mstr_standard","I200";
;
CDS_LIB"mstr_standard"
BODY_TYPE"PLUMBING"
HDL_TAP"TRUE";
"B \NAC \NWC"2;
"S \NAC"
BN"5"106;
%"TAP"
"1","(-3250,3875)","0","mstr_standard","I201";
;
CDS_LIB"mstr_standard"
BODY_TYPE"PLUMBING"
HDL_TAP"TRUE";
"B \NAC \NWC"2;
"S \NAC"
BN"6"123;
%"TAP"
"1","(-3250,3825)","0","mstr_standard","I202";
;
CDS_LIB"mstr_standard"
BODY_TYPE"PLUMBING"
HDL_TAP"TRUE";
"B \NAC \NWC"2;
"S \NAC"
BN"7"121;
%"TAP"
"1","(-3250,3725)","0","mstr_standard","I203";
;
CDS_LIB"mstr_standard"
BODY_TYPE"PLUMBING"
HDL_TAP"TRUE";
"B \NAC \NWC"2;
"S \NAC"
BN"8"119;
%"TAP"
"1","(-3250,3675)","0","mstr_standard","I204";
;
CDS_LIB"mstr_standard"
BODY_TYPE"PLUMBING"
HDL_TAP"TRUE";
"B \NAC \NWC"2;
"S \NAC"
BN"9"117;
%"TAP"
"1","(-3250,3625)","0","mstr_standard","I205";
;
CDS_LIB"mstr_standard"
BODY_TYPE"PLUMBING"
HDL_TAP"TRUE";
"B \NAC \NWC"2;
"S \NAC"
BN"10"109;
%"TAP"
"1","(-3250,3575)","0","mstr_standard","I206";
;
CDS_LIB"mstr_standard"
BODY_TYPE"PLUMBING"
HDL_TAP"TRUE";
"B \NAC \NWC"2;
"S \NAC"
BN"11"107;
%"TAP"
"1","(-3250,3525)","0","mstr_standard","I207";
;
CDS_LIB"mstr_standard"
BODY_TYPE"PLUMBING"
HDL_TAP"TRUE";
"B \NAC \NWC"2;
"S \NAC"
BN"12"124;
%"TAP"
"1","(-3250,3475)","0","mstr_standard","I208";
;
CDS_LIB"mstr_standard"
BODY_TYPE"PLUMBING"
HDL_TAP"TRUE";
"B \NAC \NWC"2;
"S \NAC"
BN"13"122;
%"TAP"
"1","(-3250,3375)","0","mstr_standard","I209";
;
CDS_LIB"mstr_standard"
BODY_TYPE"PLUMBING"
HDL_TAP"TRUE";
"B \NAC \NWC"2;
"S \NAC"
BN"15"118;
%"TAP"
"1","(-3250,3425)","0","mstr_standard","I210";
;
CDS_LIB"mstr_standard"
BODY_TYPE"PLUMBING"
HDL_TAP"TRUE";
"B \NAC \NWC"2;
"S \NAC"
BN"14"120;
%"TAP"
"1","(-3250,3275)","0","mstr_standard","I211";
;
CDS_LIB"mstr_standard"
BODY_TYPE"PLUMBING"
HDL_TAP"TRUE";
"B \NAC \NWC"2;
"S \NAC"
BN"16"116;
%"TAP"
"1","(-3250,3225)","0","mstr_standard","I212";
;
CDS_LIB"mstr_standard"
BODY_TYPE"PLUMBING"
HDL_TAP"TRUE";
"B \NAC \NWC"2;
"S \NAC"
BN"17"115;
%"TAP"
"1","(-3250,3175)","0","mstr_standard","I213";
;
CDS_LIB"mstr_standard"
BODY_TYPE"PLUMBING"
HDL_TAP"TRUE";
"B \NAC \NWC"2;
"S \NAC"
BN"18"114;
%"TAP"
"1","(-3250,3125)","0","mstr_standard","I214";
;
CDS_LIB"mstr_standard"
BODY_TYPE"PLUMBING"
HDL_TAP"TRUE";
"B \NAC \NWC"2;
"S \NAC"
BN"19"113;
%"TAP"
"1","(-3250,3075)","0","mstr_standard","I215";
;
CDS_LIB"mstr_standard"
BODY_TYPE"PLUMBING"
HDL_TAP"TRUE";
"B \NAC \NWC"2;
"S \NAC"
BN"20"111;
%"TAP"
"1","(-3250,2975)","0","mstr_standard","I216";
;
CDS_LIB"mstr_standard"
BODY_TYPE"PLUMBING"
HDL_TAP"TRUE";
"B \NAC \NWC"2;
"S \NAC"
BN"22"88;
%"TAP"
"1","(-3250,3025)","0","mstr_standard","I217";
;
CDS_LIB"mstr_standard"
BODY_TYPE"PLUMBING"
HDL_TAP"TRUE";
"B \NAC \NWC"2;
"S \NAC"
BN"21"89;
%"TAP"
"1","(-3250,2925)","0","mstr_standard","I218";
;
CDS_LIB"mstr_standard"
BODY_TYPE"PLUMBING"
HDL_TAP"TRUE";
"B \NAC \NWC"2;
"S \NAC"
BN"23"105;
%"TAP"
"1","(-3250,2825)","0","mstr_standard","I219";
;
CDS_LIB"mstr_standard"
BODY_TYPE"PLUMBING"
HDL_TAP"TRUE";
"B \NAC \NWC"2;
"S \NAC"
BN"24"104;
%"TAP"
"1","(-3250,2775)","0","mstr_standard","I220";
;
CDS_LIB"mstr_standard"
BODY_TYPE"PLUMBING"
HDL_TAP"TRUE";
"B \NAC \NWC"2;
"S \NAC"
BN"25"103;
%"TAP"
"1","(-3250,2725)","0","mstr_standard","I221";
;
CDS_LIB"mstr_standard"
BODY_TYPE"PLUMBING"
HDL_TAP"TRUE";
"B \NAC \NWC"2;
"S \NAC"
BN"26"102;
%"TAP"
"1","(-3250,2575)","0","mstr_standard","I222";
;
CDS_LIB"mstr_standard"
BODY_TYPE"PLUMBING"
HDL_TAP"TRUE";
"B \NAC \NWC"2;
"S \NAC"
BN"29"99;
%"TAP"
"1","(-3250,2625)","0","mstr_standard","I223";
;
CDS_LIB"mstr_standard"
BODY_TYPE"PLUMBING"
HDL_TAP"TRUE";
"B \NAC \NWC"2;
"S \NAC"
BN"28"100;
%"TAP"
"1","(-3250,2675)","0","mstr_standard","I224";
;
CDS_LIB"mstr_standard"
BODY_TYPE"PLUMBING"
HDL_TAP"TRUE";
"B \NAC \NWC"2;
"S \NAC"
BN"27"101;
%"TAP"
"1","(-3250,2525)","0","mstr_standard","I225";
;
CDS_LIB"mstr_standard"
BODY_TYPE"PLUMBING"
HDL_TAP"TRUE";
"B \NAC \NWC"2;
"S \NAC"
BN"30"93;
%"TAP"
"1","(-3250,2475)","0","mstr_standard","I226";
;
CDS_LIB"mstr_standard"
BODY_TYPE"PLUMBING"
HDL_TAP"TRUE";
"B \NAC \NWC"2;
"S \NAC"
BN"31"91;
%"TAP"
"1","(-3250,2325)","0","mstr_standard","I227";
;
CDS_LIB"mstr_standard"
BODY_TYPE"PLUMBING"
HDL_TAP"TRUE";
"B \NAC \NWC"3;
"S \NAC"
BN"1"97;
%"TAP"
"1","(-3250,2375)","0","mstr_standard","I228";
;
CDS_LIB"mstr_standard"
BODY_TYPE"PLUMBING"
HDL_TAP"TRUE";
"B \NAC \NWC"3;
"S \NAC"
BN"0"98;
%"TAP"
"1","(-3250,2225)","0","mstr_standard","I229";
;
CDS_LIB"mstr_standard"
BODY_TYPE"PLUMBING"
HDL_TAP"TRUE";
"B \NAC \NWC"3;
"S \NAC"
BN"3"95;
%"TAP"
"1","(-3250,2275)","0","mstr_standard","I230";
;
CDS_LIB"mstr_standard"
BODY_TYPE"PLUMBING"
HDL_TAP"TRUE";
"B \NAC \NWC"3;
"S \NAC"
BN"2"96;
%"TAP"
"1","(-3250,2075)","0","mstr_standard","I231";
;
CDS_LIB"mstr_standard"
BODY_TYPE"PLUMBING"
HDL_TAP"TRUE";
"B \NAC \NWC"3;
"S \NAC"
BN"6"90;
%"TAP"
"1","(-3250,2125)","0","mstr_standard","I232";
;
CDS_LIB"mstr_standard"
BODY_TYPE"PLUMBING"
HDL_TAP"TRUE";
"B \NAC \NWC"3;
"S \NAC"
BN"5"92;
%"TAP"
"1","(-3250,2175)","0","mstr_standard","I233";
;
CDS_LIB"mstr_standard"
BODY_TYPE"PLUMBING"
HDL_TAP"TRUE";
"B \NAC \NWC"3;
"S \NAC"
BN"4"94;
%"TAP"
"1","(-3250,1925)","0","mstr_standard","I235";
;
CDS_LIB"mstr_standard"
BODY_TYPE"PLUMBING"
HDL_TAP"TRUE";
"B \NAC \NWC"4;
"S \NAC"
BN"0"82;
%"TAP"
"1","(-3250,2025)","0","mstr_standard","I236";
;
CDS_LIB"mstr_standard"
BODY_TYPE"PLUMBING"
HDL_TAP"TRUE";
"B \NAC \NWC"3;
"S \NAC"
BN"7"80;
%"TAP"
"1","(-3250,1825)","0","mstr_standard","I237";
;
CDS_LIB"mstr_standard"
BODY_TYPE"PLUMBING"
HDL_TAP"TRUE";
"B \NAC \NWC"4;
"S \NAC"
BN"2"79;
%"TAP"
"1","(-3250,1875)","0","mstr_standard","I238";
;
CDS_LIB"mstr_standard"
BODY_TYPE"PLUMBING"
HDL_TAP"TRUE";
"B \NAC \NWC"4;
"S \NAC"
BN"1"81;
%"TAP"
"1","(-3250,1775)","0","mstr_standard","I239";
;
CDS_LIB"mstr_standard"
BODY_TYPE"PLUMBING"
HDL_TAP"TRUE";
"B \NAC \NWC"4;
"S \NAC"
BN"3"87;
%"TAP"
"1","(-3250,1725)","0","mstr_standard","I240";
;
CDS_LIB"mstr_standard"
BODY_TYPE"PLUMBING"
HDL_TAP"TRUE";
"B \NAC \NWC"4;
"S \NAC"
BN"4"86;
%"TAP"
"1","(-3250,1675)","0","mstr_standard","I241";
;
CDS_LIB"mstr_standard"
BODY_TYPE"PLUMBING"
HDL_TAP"TRUE";
"B \NAC \NWC"4;
"S \NAC"
BN"5"85;
%"TAP"
"1","(-3250,1575)","0","mstr_standard","I242";
;
CDS_LIB"mstr_standard"
BODY_TYPE"PLUMBING"
HDL_TAP"TRUE";
"B \NAC \NWC"4;
"S \NAC"
BN"7"83;
%"TAP"
"1","(-3250,1625)","0","mstr_standard","I243";
;
CDS_LIB"mstr_standard"
BODY_TYPE"PLUMBING"
HDL_TAP"TRUE";
"B \NAC \NWC"4;
"S \NAC"
BN"6"84;
%"TAP"
"1","(-5675,5975)","2","mstr_standard","I244";
;
CDS_LIB"mstr_standard"
BODY_TYPE"PLUMBING"
HDL_TAP"TRUE";
"B \NAC \NWC"5;
"S \NAC"
BN"0"75;
%"TAP"
"1","(-5675,5875)","2","mstr_standard","I245";
;
CDS_LIB"mstr_standard"
BODY_TYPE"PLUMBING"
HDL_TAP"TRUE";
"B \NAC \NWC"5;
"S \NAC"
BN"1"78;
%"TAP"
"1","(-5675,5775)","2","mstr_standard","I246";
;
CDS_LIB"mstr_standard"
BODY_TYPE"PLUMBING"
HDL_TAP"TRUE";
"B \NAC \NWC"5;
"S \NAC"
BN"2"77;
%"TAP"
"1","(-5675,5675)","2","mstr_standard","I247";
;
CDS_LIB"mstr_standard"
BODY_TYPE"PLUMBING"
HDL_TAP"TRUE";
"B \NAC \NWC"5;
"S \NAC"
BN"3"76;
%"TAP"
"1","(-5675,5575)","2","mstr_standard","I248";
;
CDS_LIB"mstr_standard"
BODY_TYPE"PLUMBING"
HDL_TAP"TRUE";
"B \NAC \NWC"5;
"S \NAC"
BN"4"74;
%"TAP"
"1","(-5675,5475)","2","mstr_standard","I249";
;
CDS_LIB"mstr_standard"
BODY_TYPE"PLUMBING"
HDL_TAP"TRUE";
"B \NAC \NWC"5;
"S \NAC"
BN"5"73;
%"TAP"
"1","(-5675,5375)","2","mstr_standard","I250";
;
CDS_LIB"mstr_standard"
BODY_TYPE"PLUMBING"
HDL_TAP"TRUE";
"B \NAC \NWC"5;
"S \NAC"
BN"6"72;
%"TAP"
"1","(-5675,5275)","2","mstr_standard","I251";
;
CDS_LIB"mstr_standard"
BODY_TYPE"PLUMBING"
HDL_TAP"TRUE";
"B \NAC \NWC"5;
"S \NAC"
BN"7"71;
%"TAP"
"1","(-5675,5175)","2","mstr_standard","I252";
;
CDS_LIB"mstr_standard"
BODY_TYPE"PLUMBING"
HDL_TAP"TRUE";
"B \NAC \NWC"5;
"S \NAC"
BN"8"70;
%"TAP"
"1","(-5875,5925)","2","mstr_standard","I253";
;
CDS_LIB"mstr_standard"
BODY_TYPE"PLUMBING"
HDL_TAP"TRUE";
"B \NAC \NWC"6;
"S \NAC"
BN"0"65;
%"TAP"
"1","(-5875,5825)","2","mstr_standard","I254";
;
CDS_LIB"mstr_standard"
BODY_TYPE"PLUMBING"
HDL_TAP"TRUE";
"B \NAC \NWC"6;
"S \NAC"
BN"1"64;
%"TAP"
"1","(-5875,5725)","2","mstr_standard","I255";
;
CDS_LIB"mstr_standard"
BODY_TYPE"PLUMBING"
HDL_TAP"TRUE";
"B \NAC \NWC"6;
"S \NAC"
BN"2"63;
%"TAP"
"1","(-5875,5525)","2","mstr_standard","I256";
;
CDS_LIB"mstr_standard"
BODY_TYPE"PLUMBING"
HDL_TAP"TRUE";
"B \NAC \NWC"6;
"S \NAC"
BN"4"61;
%"TAP"
"1","(-5875,5625)","2","mstr_standard","I257";
;
CDS_LIB"mstr_standard"
BODY_TYPE"PLUMBING"
HDL_TAP"TRUE";
"B \NAC \NWC"6;
"S \NAC"
BN"3"62;
%"TAP"
"1","(-5875,5425)","2","mstr_standard","I258";
;
CDS_LIB"mstr_standard"
BODY_TYPE"PLUMBING"
HDL_TAP"TRUE";
"B \NAC \NWC"6;
"S \NAC"
BN"5"69;
%"TAP"
"1","(-5875,5325)","2","mstr_standard","I259";
;
CDS_LIB"mstr_standard"
BODY_TYPE"PLUMBING"
HDL_TAP"TRUE";
"B \NAC \NWC"6;
"S \NAC"
BN"6"68;
%"TAP"
"1","(-5875,5225)","2","mstr_standard","I260";
;
CDS_LIB"mstr_standard"
BODY_TYPE"PLUMBING"
HDL_TAP"TRUE";
"B \NAC \NWC"6;
"S \NAC"
BN"7"67;
%"TAP"
"1","(-5875,5125)","2","mstr_standard","I261";
;
CDS_LIB"mstr_standard"
BODY_TYPE"PLUMBING"
HDL_TAP"TRUE";
"B \NAC \NWC"6;
"S \NAC"
BN"8"66;
%"TAP"
"1","(-5675,5075)","2","mstr_standard","I262";
;
CDS_LIB"mstr_standard"
BODY_TYPE"PLUMBING"
HDL_TAP"TRUE";
"B \NAC \NWC"5;
"S \NAC"
BN"9"56;
%"TAP"
"1","(-5675,4925)","2","mstr_standard","I263";
;
CDS_LIB"mstr_standard"
BODY_TYPE"PLUMBING"
HDL_TAP"TRUE";
"B \NAC \NWC"7;
"S \NAC"
BN"0"60;
%"TAP"
"1","(-5675,4825)","2","mstr_standard","I264";
;
CDS_LIB"mstr_standard"
BODY_TYPE"PLUMBING"
HDL_TAP"TRUE";
"B \NAC \NWC"7;
"S \NAC"
BN"1"59;
%"TAP"
"1","(-5675,4725)","2","mstr_standard","I265";
;
CDS_LIB"mstr_standard"
BODY_TYPE"PLUMBING"
HDL_TAP"TRUE";
"B \NAC \NWC"7;
"S \NAC"
BN"2"58;
%"TAP"
"1","(-5675,4625)","2","mstr_standard","I266";
;
CDS_LIB"mstr_standard"
BODY_TYPE"PLUMBING"
HDL_TAP"TRUE";
"B \NAC \NWC"7;
"S \NAC"
BN"3"57;
%"TAP"
"1","(-5675,4525)","2","mstr_standard","I267";
;
CDS_LIB"mstr_standard"
BODY_TYPE"PLUMBING"
HDL_TAP"TRUE";
"B \NAC \NWC"7;
"S \NAC"
BN"4"55;
%"TAP"
"1","(-5675,4425)","2","mstr_standard","I268";
;
CDS_LIB"mstr_standard"
BODY_TYPE"PLUMBING"
HDL_TAP"TRUE";
"B \NAC \NWC"7;
"S \NAC"
BN"5"54;
%"TAP"
"1","(-5675,4325)","2","mstr_standard","I269";
;
CDS_LIB"mstr_standard"
BODY_TYPE"PLUMBING"
HDL_TAP"TRUE";
"B \NAC \NWC"7;
"S \NAC"
BN"6"53;
%"TAP"
"1","(-5675,4225)","2","mstr_standard","I270";
;
CDS_LIB"mstr_standard"
BODY_TYPE"PLUMBING"
HDL_TAP"TRUE";
"B \NAC \NWC"7;
"S \NAC"
BN"7"52;
%"TAP"
"1","(-5675,4125)","2","mstr_standard","I271";
;
CDS_LIB"mstr_standard"
BODY_TYPE"PLUMBING"
HDL_TAP"TRUE";
"B \NAC \NWC"7;
"S \NAC"
BN"8"51;
%"TAP"
"1","(-5875,4875)","2","mstr_standard","I272";
;
CDS_LIB"mstr_standard"
BODY_TYPE"PLUMBING"
HDL_TAP"TRUE";
"B \NAC \NWC"8;
"S \NAC"
BN"0"50;
%"TAP"
"1","(-5875,5025)","2","mstr_standard","I273";
;
CDS_LIB"mstr_standard"
BODY_TYPE"PLUMBING"
HDL_TAP"TRUE";
"B \NAC \NWC"6;
"S \NAC"
BN"9"46;
%"TAP"
"1","(-5875,4775)","2","mstr_standard","I274";
;
CDS_LIB"mstr_standard"
BODY_TYPE"PLUMBING"
HDL_TAP"TRUE";
"B \NAC \NWC"8;
"S \NAC"
BN"1"49;
%"TAP"
"1","(-5875,4675)","2","mstr_standard","I275";
;
CDS_LIB"mstr_standard"
BODY_TYPE"PLUMBING"
HDL_TAP"TRUE";
"B \NAC \NWC"8;
"S \NAC"
BN"2"48;
%"TAP"
"1","(-5875,4575)","2","mstr_standard","I276";
;
CDS_LIB"mstr_standard"
BODY_TYPE"PLUMBING"
HDL_TAP"TRUE";
"B \NAC \NWC"8;
"S \NAC"
BN"3"47;
%"TAP"
"1","(-5875,4375)","2","mstr_standard","I277";
;
CDS_LIB"mstr_standard"
BODY_TYPE"PLUMBING"
HDL_TAP"TRUE";
"B \NAC \NWC"8;
"S \NAC"
BN"5"44;
%"TAP"
"1","(-5875,4475)","2","mstr_standard","I278";
;
CDS_LIB"mstr_standard"
BODY_TYPE"PLUMBING"
HDL_TAP"TRUE";
"B \NAC \NWC"8;
"S \NAC"
BN"4"45;
%"TAP"
"1","(-5875,4275)","2","mstr_standard","I279";
;
CDS_LIB"mstr_standard"
BODY_TYPE"PLUMBING"
HDL_TAP"TRUE";
"B \NAC \NWC"8;
"S \NAC"
BN"6"43;
%"TAP"
"1","(-5875,4175)","2","mstr_standard","I280";
;
CDS_LIB"mstr_standard"
BODY_TYPE"PLUMBING"
HDL_TAP"TRUE";
"B \NAC \NWC"8;
"S \NAC"
BN"7"42;
%"TAP"
"1","(-5675,4025)","2","mstr_standard","I285";
;
CDS_LIB"mstr_standard"
BODY_TYPE"PLUMBING"
HDL_TAP"TRUE";
"B \NAC \NWC"7;
"S \NAC"
BN"9"41;
%"TAP"
"1","(-5875,4075)","2","mstr_standard","I286";
;
CDS_LIB"mstr_standard"
BODY_TYPE"PLUMBING"
HDL_TAP"TRUE";
"B \NAC \NWC"8;
"S \NAC"
BN"8"26;
%"TAP"
"1","(-5875,3975)","2","mstr_standard","I287";
;
CDS_LIB"mstr_standard"
BODY_TYPE"PLUMBING"
HDL_TAP"TRUE";
"B \NAC \NWC"8;
"S \NAC"
BN"9"25;
%"TAP"
"1","(-5875,3825)","2","mstr_standard","I288";
;
CDS_LIB"mstr_standard"
BODY_TYPE"PLUMBING"
HDL_TAP"TRUE";
"B \NAC \NWC"9;
"S \NAC"
BN"0"40;
%"TAP"
"1","(-5875,3775)","2","mstr_standard","I289";
;
CDS_LIB"mstr_standard"
BODY_TYPE"PLUMBING"
HDL_TAP"TRUE";
"B \NAC \NWC"9;
"S \NAC"
BN"1"38;
%"TAP"
"1","(-5875,3725)","2","mstr_standard","I290";
;
CDS_LIB"mstr_standard"
BODY_TYPE"PLUMBING"
HDL_TAP"TRUE";
"B \NAC \NWC"9;
"S \NAC"
BN"2"36;
%"TAP"
"1","(-5875,3625)","2","mstr_standard","I291";
;
CDS_LIB"mstr_standard"
BODY_TYPE"PLUMBING"
HDL_TAP"TRUE";
"B \NAC \NWC"9;
"S \NAC"
BN"4"32;
%"TAP"
"1","(-5875,3675)","2","mstr_standard","I292";
;
CDS_LIB"mstr_standard"
BODY_TYPE"PLUMBING"
HDL_TAP"TRUE";
"B \NAC \NWC"9;
"S \NAC"
BN"3"34;
%"TAP"
"1","(-5875,3525)","2","mstr_standard","I293";
;
CDS_LIB"mstr_standard"
BODY_TYPE"PLUMBING"
HDL_TAP"TRUE";
"B \NAC \NWC"9;
"S \NAC"
BN"6"28;
%"TAP"
"1","(-5875,3575)","2","mstr_standard","I294";
;
CDS_LIB"mstr_standard"
BODY_TYPE"PLUMBING"
HDL_TAP"TRUE";
"B \NAC \NWC"9;
"S \NAC"
BN"5"30;
%"TAP"
"1","(-5875,3375)","2","mstr_standard","I295";
;
CDS_LIB"mstr_standard"
BODY_TYPE"PLUMBING"
HDL_TAP"TRUE";
"B \NAC \NWC"10;
"S \NAC"
BN"1"37;
%"TAP"
"1","(-5875,3425)","2","mstr_standard","I296";
;
CDS_LIB"mstr_standard"
BODY_TYPE"PLUMBING"
HDL_TAP"TRUE";
"B \NAC \NWC"10;
"S \NAC"
BN"0"39;
%"TAP"
"1","(-5875,3325)","2","mstr_standard","I297";
;
CDS_LIB"mstr_standard"
BODY_TYPE"PLUMBING"
HDL_TAP"TRUE";
"B \NAC \NWC"10;
"S \NAC"
BN"2"35;
%"TAP"
"1","(-5875,3275)","2","mstr_standard","I298";
;
CDS_LIB"mstr_standard"
BODY_TYPE"PLUMBING"
HDL_TAP"TRUE";
"B \NAC \NWC"10;
"S \NAC"
BN"3"33;
%"TAP"
"1","(-5875,3225)","2","mstr_standard","I299";
;
CDS_LIB"mstr_standard"
BODY_TYPE"PLUMBING"
HDL_TAP"TRUE";
"B \NAC \NWC"10;
"S \NAC"
BN"4"31;
%"TAP"
"1","(-5875,3125)","2","mstr_standard","I300";
;
CDS_LIB"mstr_standard"
BODY_TYPE"PLUMBING"
HDL_TAP"TRUE";
"B \NAC \NWC"10;
"S \NAC"
BN"6"27;
%"TAP"
"1","(-5875,3175)","2","mstr_standard","I301";
;
CDS_LIB"mstr_standard"
BODY_TYPE"PLUMBING"
HDL_TAP"TRUE";
"B \NAC \NWC"10;
"S \NAC"
BN"5"29;
%"Q_RES"
"1","(-6800,2125)","0","pure_quanta","I314";
;
LOCATION"R383"
$SEC"1"
CDS_SEC"1"
PACK_TYPE"0402LF"
TOLERANCE"1%"
VALUE"15"
MATERIAL"CHIP"
WATTAGE"1/16W"
CDS_LIB"pure_quanta"
PART_NUMBER"CS01502FB03";
"B"
$PN"2"12;
"A"
$PN"1"11;
END.
